#ISCELL
  mstr_misc dns *
  *
#ISCELL
  pure_quanta quanta_title_block_c *
  *
#ISCELL
  pure_quanta_power universal_gnd *
  page197_i1
#ISCELL
  pure_quanta_power vcc_core *
  page197_i100
#ISCELL
  pure_quanta_power vcc_core *
  page197_i101
#CELL
  pure_quanta q_cap *
  page197_i105
#CELL
  pure_quanta q_cap *
  page197_i106
#CELL
  pure_quanta q_res *
  page197_i107
#CELL
  pure_quanta q_res *
  page197_i108
#CELL
  pure_quanta q_cap *
  page197_i109
#CELL
  pure_quanta q_cap *
  page197_i110
#CELL
  pure_quanta q_inductor4p_14 *
  page197_i111
#CELL
  pure_quanta q_inductor4p_14 *
  page197_i112
#CELL
  pure_quanta q_res *
  page197_i113
#CELL
  pure_quanta q_capp *
  page197_i115
#ISCELL
  standard offpage *
  page197_i116
#ISCELL
  standard offpage *
  page197_i117
#CELL
  pure_quanta q_capp *
  page197_i118
#CELL
  pure_quanta q_cap *
  page197_i119
#CELL
  pure_quanta q_cap *
  page197_i120
#CELL
  pure_quanta q_cap *
  page197_i121
#ISCELL
  pure_quanta_power universal_gnd *
  page197_i122
#ISCELL
  pure_quanta_power universal_gnd *
  page197_i123
#CELL
  pure_quanta q_res *
  page197_i124
#CELL
  pure_quanta q_cap *
  page197_i125
#CELL
  pure_quanta q_cap *
  page197_i127
#ISCELL
  pure_quanta_power universal_gnd *
  page197_i128
#ISCELL
  pure_quanta_power universal_gnd *
  page197_i129
#ISCELL
  pure_quanta_power universal_gnd *
  page197_i13
#CELL
  pure_quanta q_res *
  page197_i130
#CELL
  pure_quanta q_cap *
  page197_i131
#ISCELL
  pure_quanta_power universal_gnd *
  page197_i133
#ISCELL
  pure_quanta_power universal_gnd *
  page197_i134
#ISCELL
  standard offpage *
  page197_i135
#ISCELL
  pure_quanta_power universal_gnd *
  page197_i136
#CELL
  pure_quanta q_res *
  page197_i137
#CELL
  pure_quanta q_cap *
  page197_i138
#CELL
  pure_quanta q_cap *
  page197_i139
#CELL
  pure_quanta q_res *
  page197_i140
#ISCELL
  pure_quanta_power universal_gnd *
  page197_i141
#ISCELL
  pure_quanta_power vcc_core *
  page197_i142
#ISCELL
  pure_quanta_power vcc_core *
  page197_i143
#CELL
  pure_quanta q_res *
  page197_i144
#ISCELL
  standard offpage *
  page197_i145
#ISCELL
  pure_quanta_power universal_gnd *
  page197_i146
#ISCELL
  standard offpage *
  page197_i16
#CELL
  pure_quanta q_res *
  page197_i17
#CELL
  pure_quanta q_res *
  page197_i2
#ISCELL
  standard offpage *
  page197_i20
#ISCELL
  standard offpage *
  page197_i21
#CELL
  pure_quanta isl99390frztr5935 *
  page197_i30
#ISCELL
  pure_quanta_power universal_gnd *
  page197_i31
#ISCELL
  pure_quanta_power universal_gnd *
  page197_i34
#CELL
  pure_quanta isl99390frztr5935 *
  page197_i35
#CELL
  pure_quanta q_cap *
  page197_i39
#ISCELL
  standard offpage *
  page197_i4
#CELL
  pure_quanta q_cap *
  page197_i41
#CELL
  pure_quanta q_cap *
  page197_i42
#ISCELL
  pure_quanta_power universal_gnd *
  page197_i44
#CELL
  pure_quanta q_cap *
  page197_i50
#CELL
  pure_quanta q_res *
  page197_i51
#CELL
  pure_quanta q_cap *
  page197_i52
#CELL
  pure_quanta q_cap *
  page197_i56
#ISCELL
  pure_quanta_power universal_gnd *
  page197_i57
#ISCELL
  standard offpage *
  page197_i6
#CELL
  pure_quanta q_cap *
  page197_i60
#CELL
  pure_quanta q_cap *
  page197_i61
#ISCELL
  pure_quanta_power vcc_core *
  page197_i64
#CELL
  pure_quanta q_capp *
  page197_i66
#ISCELL
  pure_quanta_power universal_gnd *
  page197_i67
#CELL
  pure_quanta q_capp *
  page197_i68
#ISCELL
  pure_quanta_power vcc_core *
  page197_i69
#ISCELL
  standard offpage *
  page197_i7
#CELL
  pure_quanta q_cap *
  page197_i70
#ISCELL
  pure_quanta_power vcc_core *
  page197_i71
#CELL
  pure_quanta q_cap *
  page197_i72
#CELL
  pure_quanta q_cap *
  page197_i73
#CELL
  pure_quanta q_inductor *
  page197_i74
#ISCELL
  pure_quanta_power universal_gnd *
  page197_i75
#ISCELL
  pure_quanta_power vcc_core *
  page197_i76
#ISCELL
  pure_quanta_power universal_gnd *
  page197_i80
#CELL
  pure_quanta q_cap *
  page197_i85
#CELL
  pure_quanta q_cap *
  page197_i86
#ISCELL
  standard offpage *
  page197_i99
